FILE_TYPE = CONNECTIVITY;
{Allegro Design Entry HDL 17.4-2019 S026 (4007227) 1/17/2022}
"PAGE_NUMBER" = 160;
0"NC";
1"GND\g";
2"P3V3_AUX\g";
3"P3V3_9ZXL045_P0_VDDR\g";
4"GND\g";
5"P3V3_AUX\g";
6"P3V3_9ZXL045_P0_VDDA\g";
7"P3V3_AUX\g";
8"NC_U314_FBOUT_N";
9"NC_U314_NC0";
10"NC_U314_NC3";
11"GND\g";
12"GND\g";
13"CLK_9ZXL045_P0_SADR0";
14"P3V3_9ZXL045_P0_VDD\g";
15"GND\g";
16"P3V3_9ZXL045_P0_VDDA\g";
17"P3V3_AUX\g";
18"P3V3_AUX\g";
19"P3V3_9ZXL045_P0_VDD\g";
20"GND\g";
21"P3V3_9ZXL045_P0_VDDR\g";
22"GND\g";
23"CLK_9ZXL045_P0_SADR0";
24"CLK_9ZXL045_P0_HIBW";
25"CLK_9ZXL045_P0_HIBW";
26"CLK_100M_CPU0_CLK13_DN";
27"SMB_9ZXL045_P0_SDA";
28"P3V3_9ZXL045_P0";
29"SMB_9ZXL045_P0_SCL";
30"FM_9ZXL045_P0_DEV_EN";
31"NC_U314_FBOUT";
32"NC_U314_NC1";
33"NC_U314_NC2";
34"FM_9ZXL045_P0_2_OE_N";
35"FM_9ZXL045_P0_1_OE_N";
36"FM_9ZXL045_P0_0_OE_N";
37"CLK_100M_RETIMER_CPU0_P3_R_DN";
38"CLK_100M_RETIMER_CPU0_P2_R_DN";
39"CLK_100M_RETIMER_CPU0_P1_R_DN";
40"CLK_100M_RETIMER_CPU0_P1_R_DP";
41"CLK_100M_CPU0_CLK13_DP";
42"CLK_100M_RETIMER_CPU0_P3_R_DP";
43"CLK_100M_RETIMER_CPU0_P0_R_DN";
44"CLK_100M_RETIMER_CPU0_P2_R_DP";
45"CLK_100M_RETIMER_CPU0_P0_R_DP";
46"FM_9ZXL045_P0_3_OE_N";
%"UNIVERSAL_GND"
"1","(-6250,1125)","0","pure_quanta_power","I1";
;
CDS_LIB"pure_quanta_power"
HDL_POWER"GND";
"A"1;
%"UNIVERSAL_POWER"
"1","(-6250,2150)","0","pure_quanta_power","I14";
;
HDL_POWER"P3V3_AUX"
CDS_LIB"pure_quanta_power";
"A"2;
%"UNIVERSAL_GND"
"1","(-7125,4700)","0","pure_quanta_power","I16";
;
CDS_LIB"pure_quanta_power"
HDL_POWER"GND";
"A"22;
%"UNIVERSAL_POWER"
"1","(-7125,5325)","0","pure_quanta_power","I17";
;
HDL_POWER"P3V3_9ZXL045_P0_VDDR"
CDS_LIB"pure_quanta_power";
"A"21;
%"Q_CAP"
"1","(-7125,5075)","0","pure_quanta","I18";
;
LOCATION"C78"
$SEC"1"
CDS_SEC"1"
MATERIAL"X7R"
PACK_TYPE"0402"
TOLERANCE"10%"
VOLTAGE"25V"
VALUE"0.1UF"
CDS_LIB"pure_quanta"
PART_NUMBER"CH4104K1B00";
"B"
$PN"2"22;
"A"
$PN"1"21;
%"UNIVERSAL_GND"
"1","(-7150,5500)","0","pure_quanta_power","I19";
;
CDS_LIB"pure_quanta_power"
HDL_POWER"GND";
"A"20;
%"Q_RES"
"2","(-6250,1375)","0","pure_quanta","I2";
;
LOCATION"R4490"
$SEC"1"
CDS_SEC"1"
TOLERANCE"1%"
PACK_TYPE"0402LF"
MATERIAL"EMPTY"
WATTAGE"1/16W"
VALUE"4.75K"
CDS_LIB"pure_quanta"
PART_NUMBER"CS24752FB03";
"A"
$PN"1"13;
"B"
$PN"2"1;
%"Q_CAP"
"1","(-7150,5875)","0","pure_quanta","I20";
;
LOCATION"C2334"
$SEC"1"
CDS_SEC"1"
MATERIAL"X7R"
VOLTAGE"25V"
VALUE"0.1UF"
TOLERANCE"10%"
PACK_TYPE"0402"
CDS_LIB"pure_quanta"
PART_NUMBER"CH4104K1B00";
"B"
$PN"2"20;
"A"
$PN"1"16;
%"UNIVERSAL_POWER"
"1","(-6175,4300)","0","pure_quanta_power","I21";
;
HDL_POWER"P3V3_9ZXL045_P0_VDDR"
CDS_LIB"pure_quanta_power";
"A"3;
%"UNIVERSAL_POWER"
"1","(-5775,4600)","0","pure_quanta_power","I22";
;
HDL_POWER"P3V3_9ZXL045_P0_VDD"
CDS_LIB"pure_quanta_power";
"A"19;
%"UNIVERSAL_POWER"
"1","(-5900,5850)","0","pure_quanta_power","I23";
;
HDL_POWER"P3V3_AUX"
CDS_LIB"pure_quanta_power";
"A"18;
%"Q_INDUCTOR"
"1","(-5450,5750)","0","pure_quanta","I24";
;
LOCATION"L20"
$SEC"1"
CDS_SEC"1"
MATERIAL"IND"
PACK_TYPE"SMLF"
VALUE"FCM2012KF-601T/0.5A"
NEEDS_NO_SIZE"TRUE"
CDS_LIB"pure_quanta"
PART_NUMBER"CX601T05003";
"1"
$PN"1"18;
"2"
$PN"2"14;
%"UNIVERSAL_POWER"
"1","(-9200,6150)","0","pure_quanta_power","I25";
;
HDL_POWER"P3V3_AUX"
CDS_LIB"pure_quanta_power";
"A"17;
%"Q_INDUCTOR"
"1","(-8775,6075)","0","pure_quanta","I26";
;
LOCATION"L19"
$SEC"1"
CDS_SEC"1"
MATERIAL"IND"
PACK_TYPE"SMLF"
VALUE"FCM2012KF-601T/0.5A"
CDS_LIB"pure_quanta"
NEEDS_NO_SIZE"TRUE"
PART_NUMBER"CX601T05003";
"1"
$PN"1"17;
"2"
$PN"2"28;
%"Q_RES"
"1","(-7925,6050)","0","pure_quanta","I27";
;
LOCATION"R4493"
SEC"1"
MATERIAL"CHIP"
PACK_TYPE"0603LF"
TOLERANCE"1%"
VALUE"1"
WATTAGE"1/10W"
SEC_TYPE"0603LF"
CDS_LIB"pure_quanta"
PART_NUMBER"CS-1003F900";
"B"
$PN"2"16;
"A"
$PN"1"28;
%"UNIVERSAL_POWER"
"1","(-7150,6125)","0","pure_quanta_power","I28";
;
HDL_POWER"P3V3_9ZXL045_P0_VDDA"
CDS_LIB"pure_quanta_power";
"A"16;
%"Q_RES"
"2","(-4250,1325)","0","pure_quanta","I29";
;
LOCATION"R4492"
$SEC"1"
CDS_SEC"1"
TOLERANCE"1%"
PACK_TYPE"0402LF"
VALUE"10K"
WATTAGE"1/16W"
MATERIAL"CHIP"
CDS_LIB"pure_quanta"
PART_NUMBER"CS31002FB08";
"A"
$PN"1"24;
"B"
$PN"2"4;
%"Q_RES"
"2","(-6250,1800)","0","pure_quanta","I3";
;
LOCATION"R4489"
$SEC"1"
CDS_SEC"1"
MATERIAL"CHIP"
PACK_TYPE"0402LF"
VALUE"4.75K"
TOLERANCE"1%"
WATTAGE"1/16W"
CDS_LIB"pure_quanta"
PART_NUMBER"CS24752FB03";
"A"
$PN"1"2;
"B"
$PN"2"13;
%"UNIVERSAL_GND"
"1","(-4250,1075)","0","pure_quanta_power","I30";
;
CDS_LIB"pure_quanta_power"
HDL_POWER"GND";
"A"4;
%"Q_RES"
"2","(-4250,1800)","0","pure_quanta","I31";
;
LOCATION"R4491"
$SEC"1"
CDS_SEC"1"
WATTAGE"1/16W"
MATERIAL"CHIP"
TOLERANCE"1%"
VALUE"10K"
PACK_TYPE"0402LF"
CDS_LIB"pure_quanta"
PART_NUMBER"CS31002FB08";
"A"
$PN"1"5;
"B"
$PN"2"24;
%"UNIVERSAL_POWER"
"1","(-4250,2100)","0","pure_quanta_power","I33";
;
HDL_POWER"P3V3_AUX"
CDS_LIB"pure_quanta_power";
"A"5;
%"UNIVERSAL_GND"
"1","(-4025,2775)","0","pure_quanta_power","I34";
;
CDS_LIB"pure_quanta_power"
HDL_POWER"GND";
"A"12;
%"Q_CAP"
"1","(-4575,5525)","0","pure_quanta","I40";
;
LOCATION"C2329"
$SEC"1"
CDS_SEC"1"
PACK_TYPE"0402"
MATERIAL"X7R"
TOLERANCE"10%"
VALUE"0.1UF"
VOLTAGE"25V"
CDS_LIB"pure_quanta"
PART_NUMBER"CH4104K1B00";
"B"
$PN"2"15;
"A"
$PN"1"14;
%"Q_CAP"
"1","(-4325,5525)","0","pure_quanta","I41";
;
LOCATION"C79"
$SEC"1"
CDS_SEC"1"
VOLTAGE"25V"
TOLERANCE"10%"
PACK_TYPE"0402"
VALUE"0.1UF"
MATERIAL"X7R"
CDS_LIB"pure_quanta"
PART_NUMBER"CH4104K1B00";
"B"
$PN"2"15;
"A"
$PN"1"14;
%"UNIVERSAL_POWER"
"1","(-3900,4600)","0","pure_quanta_power","I42";
;
HDL_POWER"P3V3_9ZXL045_P0_VDDA"
CDS_LIB"pure_quanta_power";
"A"6;
%"Q_CAP"
"1","(-4075,5525)","0","pure_quanta","I44";
;
LOCATION"C80"
$SEC"1"
CDS_SEC"1"
VALUE"0.1UF"
PACK_TYPE"0402"
TOLERANCE"10%"
VOLTAGE"25V"
MATERIAL"X7R"
CDS_LIB"pure_quanta"
PART_NUMBER"CH4104K1B00";
"B"
$PN"2"15;
"A"
$PN"1"14;
%"Q_CAP"
"1","(-3825,5525)","0","pure_quanta","I45";
;
LOCATION"C81"
$SEC"1"
CDS_SEC"1"
VOLTAGE"25V"
PACK_TYPE"0402"
VALUE"0.1UF"
TOLERANCE"10%"
MATERIAL"X7R"
CDS_LIB"pure_quanta"
PART_NUMBER"CH4104K1B00";
"B"
$PN"2"15;
"A"
$PN"1"14;
%"UNIVERSAL_GND"
"1","(-3550,5175)","0","pure_quanta_power","I46";
;
CDS_LIB"pure_quanta_power"
HDL_POWER"GND";
"A"15;
%"Q_CAP"
"1","(-3550,5525)","0","pure_quanta","I47";
;
LOCATION"C2339"
$SEC"1"
CDS_SEC"1"
VOLTAGE"25V"
VALUE"0.1UF"
PACK_TYPE"0402"
MATERIAL"X7R"
TOLERANCE"10%"
CDS_LIB"pure_quanta"
PART_NUMBER"CH4104K1B00";
"B"
$PN"2"15;
"A"
$PN"1"14;
%"UNIVERSAL_POWER"
"1","(-3550,5875)","0","pure_quanta_power","I48";
;
HDL_POWER"P3V3_9ZXL045_P0_VDD"
CDS_LIB"pure_quanta_power";
"A"14;
%"Q_RES"
"2","(-3150,3075)","0","pure_quanta","I52";
;
LOCATION"R4518"
$SEC"1"
CDS_SEC"1"
PACK_TYPE"0402LF"
TOLERANCE"1%"
VALUE"10K"
WATTAGE"1/16W"
MATERIAL"CHIP"
CDS_LIB"pure_quanta"
PART_NUMBER"CS31002FB08";
"A"
$PN"1"34;
"B"
$PN"2"11;
%"Q_RES"
"2","(-2925,3075)","0","pure_quanta","I53";
;
LOCATION"R4519"
$SEC"1"
CDS_SEC"1"
PACK_TYPE"0402LF"
TOLERANCE"1%"
VALUE"10K"
MATERIAL"CHIP"
WATTAGE"1/16W"
CDS_LIB"pure_quanta"
PART_NUMBER"CS31002FB08";
"A"
$PN"1"35;
"B"
$PN"2"11;
%"Q_RES"
"2","(-2725,3100)","0","pure_quanta","I55";
;
LOCATION"R4520"
$SEC"1"
CDS_SEC"1"
MATERIAL"CHIP"
WATTAGE"1/16W"
PACK_TYPE"0402LF"
TOLERANCE"1%"
VALUE"10K"
CDS_LIB"pure_quanta"
PART_NUMBER"CS31002FB08";
"A"
$PN"1"36;
"B"
$PN"2"11;
%"Q_RES"
"1","(-7875,5225)","0","pure_quanta","I6";
;
LOCATION"R4475"
SEC"1"
PACK_TYPE"0603LF"
WATTAGE"1/10W"
MATERIAL"CHIP"
TOLERANCE"1%"
VALUE"1"
SEC_TYPE"0603LF"
CDS_LIB"pure_quanta"
PART_NUMBER"CS-1003F900";
"B"
$PN"2"21;
"A"
$PN"1"28;
%"9ZXL0451EKILFT"
"1","(-4850,3700)","0","pure_quanta","I63";
;
LOCATION"U314"
$SEC"1"
CDS_SEC"1"
VALUE"9ZXL0451EKILFT"
PART_TYPE"SMLF"
MATERIAL"IC"
CDS_LMAN_SYM_OUTLINE"-475,725,475,-725"
NEEDS_NO_SIZE"TRUE"
CDS_LIB"pure_quanta"
PART_NUMBER"AL000451003";
"VSADR0_TRI"
$PN"5"23;
"NC2"
$PN"17"33;
"NC3"
$PN"30"10;
"VDD0"
$PN"12"19;
"DIF3"
$PN"27"42;
"DIF1"
$PN"19"40;
"EPAD_GND"
$PN"33"12;
"^HIBW_BYPM_LOBW# \B"
$PN"32"25;
"VDD1"
$PN"16"19;
"VDDA"
$PN"31"6;
"NC0"
$PN"10"9;
"DIF3# \B"
$PN"28"37;
"DIF2# \B"
$PN"23"38;
"VOE2# \B"
$PN"24"34;
"DIF2"
$PN"22"44;
"DIF1# \B"
$PN"20"39;
"VOE1# \B"
$PN"18"35;
"DIF0"
$PN"13"45;
"DIF0# \B"
$PN"14"43;
"^CKPWRGD_PD# \B"
$PN"1"30;
"VDD2"
$PN"21"19;
"SMBCLK"
$PN"7"29;
"FBOUT_NC# \B"
$PN"8"8;
"NC1"
$PN"11"32;
"SMBDAT"
$PN"6"27;
"VOE3# \B"
$PN"26"46;
"VOE0# \B"
$PN"15"36;
"FBOUT_NC"
$PN"9"31;
"VDD4"
$PN"29"19;
"VDD3"
$PN"25"19;
"VDDR"
$PN"2"3;
"DIF_IN# \B"
$PN"4"26;
"DIF_IN"
$PN"3"41;
%"Q_RES"
"2","(-3375,3075)","0","pure_quanta","I68";
;
LOCATION"R6802"
$SEC"1"
CDS_SEC"1"
MATERIAL"CHIP"
PACK_TYPE"0402LF"
TOLERANCE"1%"
VALUE"10K"
WATTAGE"1/16W"
CDS_LIB"pure_quanta"
PART_NUMBER"CS31002FB08";
"A"
$PN"1"46;
"B"
$PN"2"11;
%"Q_CAP"
"1","(-7500,5875)","0","pure_quanta","I69";
;
LOCATION"C76"
$SEC"1"
CDS_SEC"1"
VOLTAGE"6.3V"
VALUE"10UF"
MATERIAL"X6S"
PACK_TYPE"C0402"
TOLERANCE"20%"
CDS_LIB"pure_quanta"
PART_NUMBER"CH6101MEB01";
"B"
$PN"2"20;
"A"
$PN"1"16;
%"Q_CAP"
"1","(-7475,5075)","0","pure_quanta","I70";
;
LOCATION"C77"
$SEC"1"
CDS_SEC"1"
VALUE"10UF"
MATERIAL"X6S"
TOLERANCE"20%"
VOLTAGE"6.3V"
PACK_TYPE"C0402"
CDS_LIB"pure_quanta"
PART_NUMBER"CH6101MEB01";
"B"
$PN"2"22;
"A"
$PN"1"21;
%"Q_CAP"
"1","(-4925,5525)","0","pure_quanta","I71";
;
LOCATION"C2328"
$SEC"1"
CDS_SEC"1"
TOLERANCE"20%"
MATERIAL"X6S"
PACK_TYPE"C0402"
VALUE"10UF"
VOLTAGE"6.3V"
CDS_LIB"pure_quanta"
PART_NUMBER"CH6101MEB01";
"B"
$PN"2"15;
"A"
$PN"1"14;
%"UNIVERSAL_GND"
"1","(-2725,2750)","0","pure_quanta_power","I72";
;
CDS_LIB"pure_quanta_power"
HDL_POWER"GND";
"A"11;
%"Q_RES"
"2","(-7200,3700)","2","pure_quanta","I73";
;
LOCATION"R4476"
$SEC"1"
CDS_SEC"1"
PACK_TYPE"0402LF"
MATERIAL"CHIP"
VALUE"10K"
WATTAGE"1/16W"
TOLERANCE"1%"
CDS_LIB"pure_quanta"
PART_NUMBER"CS31002FB08";
"A"
$PN"1"7;
"B"
$PN"2"30;
%"UNIVERSAL_POWER"
"1","(-7200,4050)","0","pure_quanta_power","I74";
;
HDL_POWER"P3V3_AUX"
CDS_LIB"pure_quanta_power";
"A"7;
END.
